# BASEBOARD_FAB2 (Tioga Pass) — schematic netlist excerpt (pin names and nets, part order shuffled) for the footprints in the layout excerpt that follows; sources: Cadence DE-HDL packaged netlist, KiCad conversion of Wiwynn_Tioga_Pass_MB.brd

RF3  RES  1.0K 0.1% CHIP  pkg 0402  page 201 : A = VR_PVCCIN_CPU0_AIREF3 ; B = ISENSE_PVCCIN_CPU0_PH3_IMON
R4G7  RES  20.0K 1% CHIP  pkg 0402  page 233 : A = VSENSE_PVPP_GHJ ; B = VR_FB_PVPP_GHJ
R8F1  RES  10.0K 1% EMPTY  pkg 0402  page 240 : A = PWRGD_P5V_STBY ; B = GND

(kicad_pcb
	(version 20260206)
	(generator "pcbnew")
	(generator_version "10.0")
	(general
		(thickness 1.6)
		(legacy_teardrops no)
	)
	(paper "A4")
	(title_block
		(title "Wiwynn_Tioga_Pass_MB.brd")
		(comment 1 "Tioga Pass / footprints 2162-2164 of 4770")
	)
	(layers
		(0 "F.Cu" signal "TOP")
		(4 "In1.Cu" signal "L2GND")
		(6 "In2.Cu" signal "L3")
		(8 "In3.Cu" signal "L4GND")
		(10 "In4.Cu" signal "L5")
		(12 "In5.Cu" signal "L6GND")
		(14 "In6.Cu" signal "L7VCC")
		(16 "In7.Cu" signal "L8VCC")
		(18 "In8.Cu" signal "L9GND")
		(20 "In9.Cu" signal "L10")
		(22 "In10.Cu" signal "L11GND")
		(24 "In11.Cu" signal "L12")
		(26 "In12.Cu" signal "L13GND")
		(2 "B.Cu" signal "BOTTOM")
		(9 "F.Adhes" user "F.Adhesive")
		(11 "B.Adhes" user "B.Adhesive")
		(13 "F.Paste" user "Package Geometry/Pastemask Top")
		(15 "B.Paste" user "Package Geometry/Pastemask Bottom")
		(5 "F.SilkS" user "Ref Des/Silkscreen Top")
		(7 "B.SilkS" user "Ref Des/Silkscreen Bottom")
		(1 "F.Mask" user "Board Geometry/Soldermask Top")
		(3 "B.Mask" user "Board Geometry/Soldermask Bottom")
		(17 "Dwgs.User" user "User.Drawings")
		(19 "Cmts.User" user "User.Comments")
		(21 "Eco1.User" user "User.Eco1")
		(23 "Eco2.User" user "User.Eco2")
		(25 "Edge.Cuts" user "Board Geometry/Outline")
		(27 "Margin" user)
		(31 "F.CrtYd" user "Package Geometry/Place Bound Top")
		(29 "B.CrtYd" user "Package Geometry/Place Bound Bottom")
		(35 "F.Fab" user "Ref Des/Assembly Top")
		(33 "B.Fab" user "Ref Des/Assembly Bottom")
	)
	(footprint ""
		(layer "F.Cu")
		(at 168.6941 -8.763 90)
		(property "Reference" "R4G7"
			(at 0 0 90)
			(layer "F.SilkS")
			(hide yes)
			(effects
				(font
					(size 1.27 1.27)
				)
			)
		)
		(property "Value" ""
			(at 0 0 90)
			(layer "F.Fab")
			(effects
				(font
					(size 1.27 1.27)
				)
			)
		)
		(duplicate_pad_numbers_are_jumpers no)
		(fp_rect
			(start -0.2794 -0.1016)
			(end 0.2794 0.9906)
			(stroke
				(width 0)
				(type default)
			)
			(fill no)
			(layer "F.CrtYd")
		)
		(fp_line
			(start 0.2794 -0.1016)
			(end -0.2794 -0.1016)
			(stroke
				(width 0.1)
				(type default)
			)
			(layer "F.Fab")
		)
		(fp_line
			(start -0.2794 -0.1016)
			(end -0.2794 0.9906)
			(stroke
				(width 0.1)
				(type default)
			)
			(layer "F.Fab")
		)
		(fp_line
			(start 0.2794 0.9906)
			(end 0.2794 -0.1016)
			(stroke
				(width 0.1)
				(type default)
			)
			(layer "F.Fab")
		)
		(fp_line
			(start -0.2794 0.9906)
			(end 0.2794 0.9906)
			(stroke
				(width 0.1)
				(type default)
			)
			(layer "F.Fab")
		)
		(pad "1" smd rect
			(at 0 0 90)
			(size 0.508 0.508)
			(layers "F.Cu" "F.Mask" "F.Paste")
			(net "VSENSE_PVPP_GHJ")
		)
		(pad "2" smd rect
			(at 0 0.889 90)
			(size 0.508 0.508)
			(layers "F.Cu" "F.Mask" "F.Paste")
			(net "VR_FB_PVPP_GHJ")
		)
		(zone
			(layer "F.Cu")
			(hatch none 0.5)
			(connect_pads
				(clearance 0)
			)
			(min_thickness 0.25)
			(keepout
				(tracks not_allowed)
				(vias allowed)
				(pads allowed)
				(copperpour not_allowed)
				(footprints allowed)
			)
			(placement
				(enabled no)
				(sheetname "")
			)
			(fill
				(thermal_gap 0.5)
				(thermal_bridge_width 0.5)
				(island_removal_mode 0)
			)
			(polygon
				(pts
					(xy 168.9481 -8.509) (xy 169.3291 -8.509) (xy 169.3291 -9.017) (xy 168.9481 -9.017)
				)
			)
		)
		(zone
			(layer "F.Cu")
			(hatch none 0.5)
			(connect_pads
				(clearance 0)
			)
			(min_thickness 0.25)
			(keepout
				(tracks allowed)
				(vias not_allowed)
				(pads allowed)
				(copperpour not_allowed)
				(footprints allowed)
			)
			(placement
				(enabled no)
				(sheetname "")
			)
			(fill
				(thermal_gap 0.5)
				(thermal_bridge_width 0.5)
				(island_removal_mode 0)
			)
			(polygon
				(pts
					(xy 168.9481 -8.509) (xy 169.3291 -8.509) (xy 169.3291 -9.017) (xy 168.9481 -9.017)
				)
			)
		)
	)
	(footprint ""
		(layer "F.Cu")
		(at 188.500512 -67.920108 180)
		(property "Reference" "RF3"
			(at -0.8382 -0.67818 180)
			(unlocked yes)
			(layer "F.SilkS")
			(effects
				(font
					(size 0.4064 0.254)
					(thickness 0.1524)
				)
				(justify left)
			)
		)
		(property "Value" ""
			(at 0 0 180)
			(layer "F.Fab")
			(effects
				(font
					(size 1.27 1.27)
				)
			)
		)
		(duplicate_pad_numbers_are_jumpers no)
		(fp_poly
			(pts
				(xy -0.2794 -0.1016) (xy 0.2794 -0.1016) (xy 0.2794 0.9906) (xy -0.2794 0.9906)
			)
			(stroke
				(width 0)
				(type default)
			)
			(fill no)
			(layer "F.CrtYd")
		)
		(fp_line
			(start 0.2794 0.9906)
			(end 0.2794 -0.1016)
			(stroke
				(width 0.1)
				(type default)
			)
			(layer "F.Fab")
		)
		(fp_line
			(start 0.2794 -0.1016)
			(end -0.2794 -0.1016)
			(stroke
				(width 0.1)
				(type default)
			)
			(layer "F.Fab")
		)
		(fp_line
			(start -0.2794 0.9906)
			(end 0.2794 0.9906)
			(stroke
				(width 0.1)
				(type default)
			)
			(layer "F.Fab")
		)
		(fp_line
			(start -0.2794 -0.1016)
			(end -0.2794 0.9906)
			(stroke
				(width 0.1)
				(type default)
			)
			(layer "F.Fab")
		)
		(pad "1" smd rect
			(at 0 0 180)
			(size 0.508 0.508)
			(layers "F.Cu" "F.Mask" "F.Paste")
			(net "VR_PVCCIN_CPU0_AIREF3")
		)
		(pad "2" smd rect
			(at 0 0.889 180)
			(size 0.508 0.508)
			(layers "F.Cu" "F.Mask" "F.Paste")
			(net "ISENSE_PVCCIN_CPU0_PH3_IMON")
		)
		(zone
			(layer "F.Cu")
			(hatch none 0.5)
			(connect_pads
				(clearance 0)
			)
			(min_thickness 0.25)
			(keepout
				(tracks not_allowed)
				(vias allowed)
				(pads allowed)
				(copperpour not_allowed)
				(footprints allowed)
			)
			(placement
				(enabled no)
				(sheetname "")
			)
			(fill
				(thermal_gap 0.5)
				(thermal_bridge_width 0.5)
				(island_removal_mode 0)
			)
			(polygon
				(pts
					(xy 188.754512 -68.555108) (xy 188.246512 -68.555108) (xy 188.246512 -68.174108) (xy 188.754512 -68.174108)
				)
			)
		)
		(zone
			(layer "F.Cu")
			(hatch none 0.5)
			(connect_pads
				(clearance 0)
			)
			(min_thickness 0.25)
			(keepout
				(tracks allowed)
				(vias not_allowed)
				(pads allowed)
				(copperpour not_allowed)
				(footprints allowed)
			)
			(placement
				(enabled no)
				(sheetname "")
			)
			(fill
				(thermal_gap 0.5)
				(thermal_bridge_width 0.5)
				(island_removal_mode 0)
			)
			(polygon
				(pts
					(xy 188.754512 -68.174108) (xy 188.246512 -68.174108) (xy 188.246512 -68.555108) (xy 188.754512 -68.555108)
				)
			)
		)
	)
	(footprint ""
		(layer "F.Cu")
		(at 463.3849 -23.2791)
		(property "Reference" "R8F1"
			(at 0 0 0)
			(layer "F.SilkS")
			(hide yes)
			(effects
				(font
					(size 1.27 1.27)
				)
			)
		)
		(property "Value" ""
			(at 0 0 0)
			(layer "F.Fab")
			(effects
				(font
					(size 1.27 1.27)
				)
			)
		)
		(duplicate_pad_numbers_are_jumpers no)
		(fp_rect
			(start 0.2794 0.9906)
			(end -0.2794 -0.1016)
			(stroke
				(width 0)
				(type default)
			)
			(fill no)
			(layer "F.CrtYd")
		)
		(fp_line
			(start -0.2794 -0.1016)
			(end -0.2794 0.9906)
			(stroke
				(width 0.1)
				(type default)
			)
			(layer "F.Fab")
		)
		(fp_line
			(start -0.2794 0.9906)
			(end 0.2794 0.9906)
			(stroke
				(width 0.1)
				(type default)
			)
			(layer "F.Fab")
		)
		(fp_line
			(start 0.2794 -0.1016)
			(end -0.2794 -0.1016)
			(stroke
				(width 0.1)
				(type default)
			)
			(layer "F.Fab")
		)
		(fp_line
			(start 0.2794 0.9906)
			(end 0.2794 -0.1016)
			(stroke
				(width 0.1)
				(type default)
			)
			(layer "F.Fab")
		)
		(pad "1" smd rect
			(at 0 0)
			(size 0.508 0.508)
			(layers "F.Cu" "F.Mask" "F.Paste")
			(net "PWRGD_P5V_STBY")
		)
		(pad "2" smd rect
			(at 0 0.889)
			(size 0.508 0.508)
			(layers "F.Cu" "F.Mask" "F.Paste")
			(net "GND")
		)
		(zone
			(layer "F.Cu")
			(hatch none 0.5)
			(connect_pads
				(clearance 0)
			)
			(min_thickness 0.25)
			(keepout
				(tracks not_allowed)
				(vias allowed)
				(pads allowed)
				(copperpour not_allowed)
				(footprints allowed)
			)
			(placement
				(enabled no)
				(sheetname "")
			)
			(fill
				(thermal_gap 0.5)
				(thermal_bridge_width 0.5)
				(island_removal_mode 0)
			)
			(polygon
				(pts
					(xy 463.6389 -22.6441) (xy 463.6389 -23.0251) (xy 463.1309 -23.0251) (xy 463.1309 -22.6441)
				)
			)
		)
		(zone
			(layer "F.Cu")
			(hatch none 0.5)
			(connect_pads
				(clearance 0)
			)
			(min_thickness 0.25)
			(keepout
				(tracks allowed)
				(vias not_allowed)
				(pads allowed)
				(copperpour not_allowed)
				(footprints allowed)
			)
			(placement
				(enabled no)
				(sheetname "")
			)
			(fill
				(thermal_gap 0.5)
				(thermal_bridge_width 0.5)
				(island_removal_mode 0)
			)
			(polygon
				(pts
					(xy 463.6389 -22.6441) (xy 463.6389 -23.0251) (xy 463.1309 -23.0251) (xy 463.1309 -22.6441)
				)
			)
		)
	)
)
